FILE_TYPE = MULTI_PHYS_TABLE;

PART 'TPS3700DDCR'

{========================================================================================}
:VALUE         | PART_TYPE | MATERIAL | PART_NUMBER    = STANDARD    | LIFECYCLE          | PART_NUMBER   | JEDEC_TYPE  | DESCRIPTION                            | MANUFTR | MANUF_PN      | RD_CMPLS_LVL | CMPLS_LVL | FROM_PJ    | CLASS | DIP_SMD | DATA                  | EE_CHECK_LIST | FP_ECN | PSL | CREATOR | STATUS | MSD | ESD_CDM | ESD_HBM | ESD_MM | PIN_LENGTH_SHORT_PIN | PIN_LENGTH_LONG_PIN | CREATEDAY  ;
{========================================================================================}
 'TPS3700DDCR' | 'SMLF'    | 'IC'     | 'AL003700002'(!) = ''               | ''               | 'AL003700002' |'SOT23-6XF'| 'IC OTHER(6P)TPS3700DDCR(SOT-23-THIN)' | 'TIC'   | 'TPS3700DDCR' | 'EP(V1)'     | ''        | 'F0T-IVES' | 'IC'  | ''      | 'TIC_TPS3700DDCR.pdf' | ''            | ''     | ''  | ''      | ''     | ''  | ''      | ''      | ''     | '0 MILS'             | '0 MILS'            | '20220805'
 'TPS3700DDCR' | 'SMLF'    | 'EMPTY'  | 'AL003700002'(!) = ''               | ''               | 'AL003700002' |'SOT23-6XF'| 'IC OTHER(6P)TPS3700DDCR(SOT-23-THIN)' | 'TIC'   | 'TPS3700DDCR' | 'EP(V1)'     | ''        | 'F0T-IVES' | 'IC'  | ''      | 'TIC_TPS3700DDCR.pdf' | ''            | ''     | ''  | ''      | ''     | ''  | ''      | ''      | ''     | '0 MILS'             | '0 MILS'            | '20220805'

END_PART

END.

